# TIMECARD (Time Appliance Project (Time Card)) — schematic netlist excerpt (pin names and nets, part order shuffled) for the footprints in the layout excerpt that follows; sources: Cadence DE-HDL packaged netlist, KiCad conversion of R4006-B0001-02_R01.brd

R459  RESISTOR  1KOHM 1%  pkg SMC_0402R_H016  page 24 : \1\ = SG ; \2\ = UNNAMED_524_RESISTOR_I432_2
R121  RESISTOR  100OHM 1%  pkg SMC_0402R_H016  page 23 : \1\ = ANT2_OUT ; \2\ = UNNAMED_12_74HCT2G125DPTSSOP8_9

(kicad_pcb
	(version 20260206)
	(generator "pcbnew")
	(generator_version "10.0")
	(general
		(thickness 1.6)
		(legacy_teardrops no)
	)
	(paper "A4")
	(title_block
		(title "timecard-production-celestica-r4006 — R4006-B0001-02_R01.brd")
		(comment 1 "Time Appliance Project (Time Card) / footprints 232-233 of 1113")
	)
	(layers
		(0 "F.Cu" signal "TOP")
		(4 "In1.Cu" signal "L02_GND1")
		(6 "In2.Cu" signal "L03_SIG1")
		(8 "In3.Cu" signal "L04_GND2")
		(10 "In4.Cu" signal "L05_VCC1")
		(12 "In5.Cu" signal "L06_VCC2")
		(14 "In6.Cu" signal "L07_GND3")
		(16 "In7.Cu" signal "L08_SIG2")
		(18 "In8.Cu" signal "L09_GND4")
		(2 "B.Cu" signal "BOTTOM")
		(9 "F.Adhes" user "F.Adhesive")
		(11 "B.Adhes" user "B.Adhesive")
		(13 "F.Paste" user "Package Geometry/Pastemask Top")
		(15 "B.Paste" user "Package Geometry/Pastemask Bottom")
		(5 "F.SilkS" user "Ref Des/Silkscreen Top")
		(7 "B.SilkS" user "Ref Des/Silkscreen Bottom")
		(1 "F.Mask" user "Board Geometry/Soldermask Top")
		(3 "B.Mask" user "Board Geometry/Soldermask Bottom")
		(17 "Dwgs.User" user "User.Drawings")
		(19 "Cmts.User" user "User.Comments")
		(21 "Eco1.User" user "User.Eco1")
		(23 "Eco2.User" user "User.Eco2")
		(25 "Edge.Cuts" user "Board Geometry/Outline")
		(27 "Margin" user)
		(31 "F.CrtYd" user "Package Geometry/Place Bound Top")
		(29 "B.CrtYd" user "Package Geometry/Place Bound Bottom")
		(35 "F.Fab" user "Ref Des/Assembly Top")
		(33 "B.Fab" user "Ref Des/Assembly Bottom")
	)
	(footprint ""
		(layer "F.Cu")
		(at 115.1382 -81.788 180)
		(property "Reference" "R459"
			(at -0.4318 -1.18237 0)
			(unlocked yes)
			(layer "F.SilkS")
			(effects
				(font
					(size 0.7874 0.5842)
					(thickness 0.1524)
				)
			)
		)
		(property "Value" "VAL*"
			(at 0.02032 2.13233 180)
			(unlocked yes)
			(layer "F.Fab")
			(hide yes)
			(effects
				(font
					(size 0.7874 0.5842)
					(thickness 0.1524)
				)
			)
		)
		(property "Tolerance" "TOL*"
			(at 0.044704 3.05435 180)
			(unlocked yes)
			(layer "Cmts.User")
			(hide yes)
			(effects
				(font
					(size 0.7874 0.5842)
					(thickness 0.1524)
				)
			)
		)
		(property "User Part Number" "PARTNUM*"
			(at 0.02032 4.024884 180)
			(unlocked yes)
			(layer "Cmts.User")
			(hide yes)
			(effects
				(font
					(size 0.7874 0.5842)
					(thickness 0.1524)
				)
			)
		)
		(property "Device Type" "RESISTOR-G155-11001-01,1KOHM,1%"
			(at 0.008382 1.210564 180)
			(unlocked yes)
			(layer "F.Fab")
			(hide yes)
			(effects
				(font
					(size 0.7874 0.5842)
					(thickness 0.1524)
				)
			)
		)
		(duplicate_pad_numbers_are_jumpers no)
		(fp_line
			(start 1.143 0.5588)
			(end 1.143 -0.5588)
			(stroke
				(width 0.1)
				(type default)
			)
			(layer "F.SilkS")
		)
		(fp_line
			(start 1.143 -0.5588)
			(end -1.143 -0.5588)
			(stroke
				(width 0.1)
				(type default)
			)
			(layer "F.SilkS")
		)
		(fp_line
			(start -1.143 0.5588)
			(end 1.143 0.5588)
			(stroke
				(width 0.1)
				(type default)
			)
			(layer "F.SilkS")
		)
		(fp_line
			(start -1.143 -0.5588)
			(end -1.143 0.5588)
			(stroke
				(width 0.1)
				(type default)
			)
			(layer "F.SilkS")
		)
		(fp_poly
			(pts
				(xy -1.143 0.5588) (xy 1.143 0.5588) (xy 1.143 -0.5588) (xy -1.143 -0.5588)
			)
			(stroke
				(width 0)
				(type default)
			)
			(fill no)
			(layer "F.CrtYd")
		)
		(fp_line
			(start 0.508 0.3048)
			(end 0.508 -0.3048)
			(stroke
				(width 0.1)
				(type default)
			)
			(layer "F.Fab")
		)
		(fp_line
			(start 0.508 -0.3048)
			(end -0.508 -0.3048)
			(stroke
				(width 0.1)
				(type default)
			)
			(layer "F.Fab")
		)
		(fp_line
			(start -0.508 0.3048)
			(end 0.508 0.3048)
			(stroke
				(width 0.1)
				(type default)
			)
			(layer "F.Fab")
		)
		(fp_line
			(start -0.508 -0.3048)
			(end -0.508 0.3048)
			(stroke
				(width 0.1)
				(type default)
			)
			(layer "F.Fab")
		)
		(pad "1" smd rect
			(at -0.5334 0 180)
			(size 0.7112 0.6096)
			(layers "F.Cu" "F.Mask" "F.Paste")
			(net "SG")
		)
		(pad "2" smd rect
			(at 0.5334 0 180)
			(size 0.7112 0.6096)
			(layers "F.Cu" "F.Mask" "F.Paste")
			(net "UNNAMED_524_RESISTOR_I432_2")
		)
		(zone
			(layer "F.Cu")
			(hatch none 0.5)
			(connect_pads
				(clearance 0)
			)
			(min_thickness 0.25)
			(keepout
				(tracks not_allowed)
				(vias allowed)
				(pads allowed)
				(copperpour not_allowed)
				(footprints allowed)
			)
			(placement
				(enabled no)
				(sheetname "")
			)
			(fill
				(thermal_gap 0.5)
				(thermal_bridge_width 0.5)
				(island_removal_mode 0)
			)
			(polygon
				(pts
					(xy 115.2144 -82.0928) (xy 115.062 -82.0928) (xy 115.062 -81.4832) (xy 115.2144 -81.4832)
				)
			)
		)
		(zone
			(layer "F.Cu")
			(hatch none 0.5)
			(connect_pads
				(clearance 0)
			)
			(min_thickness 0.25)
			(keepout
				(tracks allowed)
				(vias not_allowed)
				(pads allowed)
				(copperpour not_allowed)
				(footprints allowed)
			)
			(placement
				(enabled no)
				(sheetname "")
			)
			(fill
				(thermal_gap 0.5)
				(thermal_bridge_width 0.5)
				(island_removal_mode 0)
			)
			(polygon
				(pts
					(xy 115.2144 -82.0928) (xy 115.062 -82.0928) (xy 115.062 -81.4832) (xy 115.2144 -81.4832)
				)
			)
		)
	)
	(footprint ""
		(layer "F.Cu")
		(at 13.462 -52.578 -90)
		(property "Reference" "R121"
			(at 0.508 3.38963 90)
			(unlocked yes)
			(layer "F.SilkS")
			(effects
				(font
					(size 0.7874 0.5842)
					(thickness 0.1524)
				)
			)
		)
		(property "Value" "VAL*"
			(at 0.02032 2.13233 270)
			(unlocked yes)
			(layer "F.Fab")
			(hide yes)
			(effects
				(font
					(size 0.7874 0.5842)
					(thickness 0.1524)
				)
			)
		)
		(property "Tolerance" "TOL*"
			(at 0.044704 3.05435 270)
			(unlocked yes)
			(layer "Cmts.User")
			(hide yes)
			(effects
				(font
					(size 0.7874 0.5842)
					(thickness 0.1524)
				)
			)
		)
		(property "User Part Number" "PARTNUM*"
			(at 0.02032 4.024884 270)
			(unlocked yes)
			(layer "Cmts.User")
			(hide yes)
			(effects
				(font
					(size 0.7874 0.5842)
					(thickness 0.1524)
				)
			)
		)
		(property "Device Type" "RESISTOR-G155-11000-01,100OHM,A"
			(at 0.008382 1.210564 270)
			(unlocked yes)
			(layer "F.Fab")
			(hide yes)
			(effects
				(font
					(size 0.7874 0.5842)
					(thickness 0.1524)
				)
			)
		)
		(duplicate_pad_numbers_are_jumpers no)
		(fp_line
			(start -1.143 0.5588)
			(end 1.143 0.5588)
			(stroke
				(width 0.1)
				(type default)
			)
			(layer "F.SilkS")
		)
		(fp_line
			(start 1.143 0.5588)
			(end 1.143 -0.5588)
			(stroke
				(width 0.1)
				(type default)
			)
			(layer "F.SilkS")
		)
		(fp_line
			(start -1.143 -0.5588)
			(end -1.143 0.5588)
			(stroke
				(width 0.1)
				(type default)
			)
			(layer "F.SilkS")
		)
		(fp_line
			(start 1.143 -0.5588)
			(end -1.143 -0.5588)
			(stroke
				(width 0.1)
				(type default)
			)
			(layer "F.SilkS")
		)
		(fp_poly
			(pts
				(xy -1.143 0.5588) (xy 1.143 0.5588) (xy 1.143 -0.5588) (xy -1.143 -0.5588)
			)
			(stroke
				(width 0)
				(type default)
			)
			(fill no)
			(layer "F.CrtYd")
		)
		(fp_line
			(start -0.508 0.3048)
			(end 0.508 0.3048)
			(stroke
				(width 0.1)
				(type default)
			)
			(layer "F.Fab")
		)
		(fp_line
			(start 0.508 0.3048)
			(end 0.508 -0.3048)
			(stroke
				(width 0.1)
				(type default)
			)
			(layer "F.Fab")
		)
		(fp_line
			(start -0.508 -0.3048)
			(end -0.508 0.3048)
			(stroke
				(width 0.1)
				(type default)
			)
			(layer "F.Fab")
		)
		(fp_line
			(start 0.508 -0.3048)
			(end -0.508 -0.3048)
			(stroke
				(width 0.1)
				(type default)
			)
			(layer "F.Fab")
		)
		(pad "1" smd rect
			(at -0.5334 0 270)
			(size 0.7112 0.6096)
			(layers "F.Cu" "F.Mask" "F.Paste")
			(net "ANT2_OUT")
		)
		(pad "2" smd rect
			(at 0.5334 0 270)
			(size 0.7112 0.6096)
			(layers "F.Cu" "F.Mask" "F.Paste")
			(net "UNNAMED_12_74HCT2G125DPTSSOP8_9")
		)
		(zone
			(layer "F.Cu")
			(hatch none 0.5)
			(connect_pads
				(clearance 0)
			)
			(min_thickness 0.25)
			(keepout
				(tracks allowed)
				(vias not_allowed)
				(pads allowed)
				(copperpour not_allowed)
				(footprints allowed)
			)
			(placement
				(enabled no)
				(sheetname "")
			)
			(fill
				(thermal_gap 0.5)
				(thermal_bridge_width 0.5)
				(island_removal_mode 0)
			)
			(polygon
				(pts
					(xy 13.1572 -52.6542) (xy 13.1572 -52.5018) (xy 13.7668 -52.5018) (xy 13.7668 -52.6542)
				)
			)
		)
		(zone
			(layer "F.Cu")
			(hatch none 0.5)
			(connect_pads
				(clearance 0)
			)
			(min_thickness 0.25)
			(keepout
				(tracks not_allowed)
				(vias allowed)
				(pads allowed)
				(copperpour not_allowed)
				(footprints allowed)
			)
			(placement
				(enabled no)
				(sheetname "")
			)
			(fill
				(thermal_gap 0.5)
				(thermal_bridge_width 0.5)
				(island_removal_mode 0)
			)
			(polygon
				(pts
					(xy 13.1572 -52.6542) (xy 13.1572 -52.5018) (xy 13.7668 -52.5018) (xy 13.7668 -52.6542)
				)
			)
		)
	)
)
